(kicad_pcb
	(version 20260206)
	(generator "pcbnew")
	(generator_version "10.0")
	(general
		(thickness 1.6)
		(legacy_teardrops no)
	)
	(paper "A4")
	(title_block
		(title "12092022_DA0F0TMDCD0_F0T_Management_Board_D_brd_V3_OCP.brd")
		(comment 1 "Grand Teton / footprints 288-293 of 1440")
	)
	(layers
		(0 "F.Cu" signal "TOP")
		(4 "In1.Cu" signal "GND")
		(6 "In2.Cu" signal "IN1")
		(8 "In3.Cu" signal "GND1")
		(10 "In4.Cu" signal "IN2")
		(12 "In5.Cu" signal "VCC")
		(14 "In6.Cu" signal "VCC1")
		(16 "In7.Cu" signal "IN3")
		(18 "In8.Cu" signal "GND2")
		(20 "In9.Cu" signal "IN4")
		(22 "In10.Cu" signal "GND3")
		(2 "B.Cu" signal "BOTTOM")
		(9 "F.Adhes" user "F.Adhesive")
		(11 "B.Adhes" user "B.Adhesive")
		(13 "F.Paste" user "Package Geometry/Pastemask Top")
		(15 "B.Paste" user "Package Geometry/Pastemask Bottom")
		(5 "F.SilkS" user "Ref Des/Silkscreen Top")
		(7 "B.SilkS" user "Ref Des/Silkscreen Bottom")
		(1 "F.Mask" user "Board Geometry/Soldermask Top")
		(3 "B.Mask" user "Board Geometry/Soldermask Bottom")
		(17 "Dwgs.User" user "User.Drawings")
		(19 "Cmts.User" user "User.Comments")
		(21 "Eco1.User" user "User.Eco1")
		(23 "Eco2.User" user "User.Eco2")
		(25 "Edge.Cuts" user "Board Geometry/Outline")
		(27 "Margin" user)
		(31 "F.CrtYd" user "Package Geometry/Place Bound Top")
		(29 "B.CrtYd" user "Package Geometry/Place Bound Bottom")
		(35 "F.Fab" user "Ref Des/Assembly Top")
		(33 "B.Fab" user "Ref Des/Assembly Bottom")
	)
	(footprint ""
		(layer "F.Cu")
		(at 13.5001 -53.6448 180)
		(property "Reference" "C305"
			(at 0 0 180)
			(layer "F.SilkS")
			(hide yes)
			(effects
				(font
					(size 1.27 1.27)
				)
			)
		)
		(property "Value" ""
			(at 0 0 180)
			(layer "F.Fab")
			(effects
				(font
					(size 1.27 1.27)
				)
			)
		)
		(duplicate_pad_numbers_are_jumpers no)
		(fp_line
			(start 0.7874 0.4064)
			(end -0.7874 0.4064)
			(stroke
				(width 0.1524)
				(type default)
			)
			(layer "F.SilkS")
		)
		(fp_line
			(start 0.7874 -0.4064)
			(end 0.7874 0.4064)
			(stroke
				(width 0.1524)
				(type default)
			)
			(layer "F.SilkS")
		)
		(fp_line
			(start -0.7874 0.4064)
			(end -0.7874 -0.4064)
			(stroke
				(width 0.1524)
				(type default)
			)
			(layer "F.SilkS")
		)
		(fp_line
			(start -0.7874 -0.4064)
			(end 0.7874 -0.4064)
			(stroke
				(width 0.1524)
				(type default)
			)
			(layer "F.SilkS")
		)
		(fp_line
			(start 0.67945 0.3048)
			(end 0.120396 0.3048)
			(stroke
				(width 0.1)
				(type default)
			)
			(layer "F.Fab")
		)
		(fp_line
			(start 0.67945 -0.3048)
			(end 0.67945 0.3048)
			(stroke
				(width 0.1)
				(type default)
			)
			(layer "F.Fab")
		)
		(fp_line
			(start 0.12065 -0.2794)
			(end 0.12065 -0.3048)
			(stroke
				(width 0.1)
				(type default)
			)
			(layer "F.Fab")
		)
		(fp_line
			(start 0.12065 -0.3048)
			(end 0.67945 -0.3048)
			(stroke
				(width 0.1)
				(type default)
			)
			(layer "F.Fab")
		)
		(fp_line
			(start 0.120396 0.3048)
			(end 0.120396 0.2794)
			(stroke
				(width 0.1)
				(type default)
			)
			(layer "F.Fab")
		)
		(fp_line
			(start 0.120396 0.2794)
			(end -0.12065 0.2794)
			(stroke
				(width 0.1)
				(type default)
			)
			(layer "F.Fab")
		)
		(fp_line
			(start -0.12065 0.3048)
			(end -0.67945 0.3048)
			(stroke
				(width 0.1)
				(type default)
			)
			(layer "F.Fab")
		)
		(fp_line
			(start -0.12065 0.2794)
			(end -0.12065 0.3048)
			(stroke
				(width 0.1)
				(type default)
			)
			(layer "F.Fab")
		)
		(fp_line
			(start -0.12065 -0.2794)
			(end 0.12065 -0.2794)
			(stroke
				(width 0.1)
				(type default)
			)
			(layer "F.Fab")
		)
		(fp_line
			(start -0.12065 -0.305054)
			(end -0.12065 -0.2794)
			(stroke
				(width 0.1)
				(type default)
			)
			(layer "F.Fab")
		)
		(fp_line
			(start -0.67945 0.3048)
			(end -0.67945 -0.305054)
			(stroke
				(width 0.1)
				(type default)
			)
			(layer "F.Fab")
		)
		(fp_line
			(start -0.67945 -0.305054)
			(end -0.12065 -0.305054)
			(stroke
				(width 0.1)
				(type default)
			)
			(layer "F.Fab")
		)
		(pad "1" smd circle
			(at -0.40005 0 180)
			(size 0 0)
			(layers "F.Cu" "F.Mask" "F.Paste")
			(net "PWRGD_P1V8_AUX_R2")
		)
		(pad "2" smd circle
			(at 0.40005 0 180)
			(size 0 0)
			(layers "F.Cu" "F.Mask" "F.Paste")
			(net "GND")
		)
	)
	(footprint ""
		(layer "F.Cu")
		(at 57.073292 -28.062936 90)
		(property "Reference" "OSC1"
			(at -2.448306 1.397508 0)
			(unlocked yes)
			(layer "F.SilkS")
			(effects
				(font
					(size 0.7874 0.5842)
					(thickness 0.1524)
				)
				(justify left)
			)
		)
		(property "Value" ""
			(at 0 0 90)
			(layer "F.Fab")
			(effects
				(font
					(size 1.27 1.27)
				)
			)
		)
		(duplicate_pad_numbers_are_jumpers no)
		(fp_line
			(start 1.397 -1.761236)
			(end -1.397 -1.761236)
			(stroke
				(width 0.1524)
				(type default)
			)
			(layer "F.SilkS")
		)
		(fp_line
			(start -1.397 -1.761236)
			(end -1.397 1.761236)
			(stroke
				(width 0.1524)
				(type default)
			)
			(layer "F.SilkS")
		)
		(fp_line
			(start 1.397 1.761236)
			(end 1.397 -1.761236)
			(stroke
				(width 0.1524)
				(type default)
			)
			(layer "F.SilkS")
		)
		(fp_line
			(start -1.397 1.761236)
			(end 1.397 1.761236)
			(stroke
				(width 0.1524)
				(type default)
			)
			(layer "F.SilkS")
		)
		(fp_poly
			(pts
				(xy -1.69037 -0.799338) (xy -2.70637 -1.307592) (xy -2.706624 -0.291592)
			)
			(stroke
				(width 0)
				(type default)
			)
			(fill yes)
			(layer "F.SilkS")
		)
		(fp_line
			(start 1.299972 -1.649984)
			(end 1.299972 1.649984)
			(stroke
				(width 0.1)
				(type default)
			)
			(layer "F.Fab")
		)
		(fp_line
			(start -1.299972 -1.649984)
			(end 1.299972 -1.649984)
			(stroke
				(width 0.1)
				(type default)
			)
			(layer "F.Fab")
		)
		(fp_line
			(start 1.299972 1.649984)
			(end -1.299972 1.649984)
			(stroke
				(width 0.1)
				(type default)
			)
			(layer "F.Fab")
		)
		(fp_line
			(start -1.299972 1.649984)
			(end -1.299972 -1.649984)
			(stroke
				(width 0.1)
				(type default)
			)
			(layer "F.Fab")
		)
		(fp_poly
			(pts
				(xy -1.694688 -1.050036) (xy -2.710688 -1.558036) (xy -2.710688 -0.542036)
			)
			(stroke
				(width 0)
				(type default)
			)
			(fill yes)
			(layer "F.Fab")
		)
		(pad "1" smd rect
			(at -0.824992 -1.050036 90)
			(size 0.8636 1.1684)
			(layers "F.Cu" "F.Mask" "F.Paste")
			(net "PU_25M_BMC_CLK_EN")
		)
		(pad "2" smd rect
			(at -0.824992 1.050036 90)
			(size 0.8636 1.1684)
			(layers "F.Cu" "F.Mask" "F.Paste")
			(net "GND")
		)
		(pad "3" smd rect
			(at 0.824992 1.050036 90)
			(size 0.8636 1.1684)
			(layers "F.Cu" "F.Mask" "F.Paste")
			(net "BMC_CLK_25M_R")
		)
		(pad "4" smd rect
			(at 0.824992 -1.050036 90)
			(size 0.8636 1.1684)
			(layers "F.Cu" "F.Mask" "F.Paste")
			(net "P3V3_RGM")
		)
	)
	(footprint ""
		(layer "F.Cu")
		(at 54.84368 -25.911556 180)
		(property "Reference" "R376"
			(at 0 0 180)
			(layer "F.SilkS")
			(hide yes)
			(effects
				(font
					(size 1.27 1.27)
				)
			)
		)
		(property "Value" ""
			(at 0 0 180)
			(layer "F.Fab")
			(effects
				(font
					(size 1.27 1.27)
				)
			)
		)
		(duplicate_pad_numbers_are_jumpers no)
		(fp_line
			(start 0.7874 0.4064)
			(end -0.7874 0.4064)
			(stroke
				(width 0.1524)
				(type default)
			)
			(layer "F.SilkS")
		)
		(fp_line
			(start 0.7874 -0.4064)
			(end 0.7874 0.4064)
			(stroke
				(width 0.1524)
				(type default)
			)
			(layer "F.SilkS")
		)
		(fp_line
			(start -0.7874 0.4064)
			(end -0.7874 -0.4064)
			(stroke
				(width 0.1524)
				(type default)
			)
			(layer "F.SilkS")
		)
		(fp_line
			(start -0.7874 -0.4064)
			(end 0.7874 -0.4064)
			(stroke
				(width 0.1524)
				(type default)
			)
			(layer "F.SilkS")
		)
		(fp_line
			(start 0.67945 0.3048)
			(end 0.120396 0.3048)
			(stroke
				(width 0.1)
				(type default)
			)
			(layer "F.Fab")
		)
		(fp_line
			(start 0.67945 -0.3048)
			(end 0.67945 0.3048)
			(stroke
				(width 0.1)
				(type default)
			)
			(layer "F.Fab")
		)
		(fp_line
			(start 0.12065 -0.2794)
			(end 0.12065 -0.3048)
			(stroke
				(width 0.1)
				(type default)
			)
			(layer "F.Fab")
		)
		(fp_line
			(start 0.12065 -0.3048)
			(end 0.67945 -0.3048)
			(stroke
				(width 0.1)
				(type default)
			)
			(layer "F.Fab")
		)
		(fp_line
			(start 0.120396 0.3048)
			(end 0.120396 0.2794)
			(stroke
				(width 0.1)
				(type default)
			)
			(layer "F.Fab")
		)
		(fp_line
			(start 0.120396 0.2794)
			(end -0.12065 0.2794)
			(stroke
				(width 0.1)
				(type default)
			)
			(layer "F.Fab")
		)
		(fp_line
			(start -0.12065 0.3048)
			(end -0.67945 0.3048)
			(stroke
				(width 0.1)
				(type default)
			)
			(layer "F.Fab")
		)
		(fp_line
			(start -0.12065 0.2794)
			(end -0.12065 0.3048)
			(stroke
				(width 0.1)
				(type default)
			)
			(layer "F.Fab")
		)
		(fp_line
			(start -0.12065 -0.2794)
			(end 0.12065 -0.2794)
			(stroke
				(width 0.1)
				(type default)
			)
			(layer "F.Fab")
		)
		(fp_line
			(start -0.12065 -0.305054)
			(end -0.12065 -0.2794)
			(stroke
				(width 0.1)
				(type default)
			)
			(layer "F.Fab")
		)
		(fp_line
			(start -0.67945 0.3048)
			(end -0.67945 -0.305054)
			(stroke
				(width 0.1)
				(type default)
			)
			(layer "F.Fab")
		)
		(fp_line
			(start -0.67945 -0.305054)
			(end -0.12065 -0.305054)
			(stroke
				(width 0.1)
				(type default)
			)
			(layer "F.Fab")
		)
		(pad "1" smd circle
			(at -0.40005 0 180)
			(size 0 0)
			(layers "F.Cu" "F.Mask" "F.Paste")
			(net "P5V_AUX")
		)
		(pad "2" smd circle
			(at 0.40005 0 180)
			(size 0 0)
			(layers "F.Cu" "F.Mask" "F.Paste")
			(net "USB_OC0_EN")
		)
	)
	(footprint ""
		(layer "F.Cu")
		(at 32.766 -12.7 180)
		(property "Reference" "R390"
			(at 0 0 180)
			(layer "F.SilkS")
			(hide yes)
			(effects
				(font
					(size 1.27 1.27)
				)
			)
		)
		(property "Value" ""
			(at 0 0 180)
			(layer "F.Fab")
			(effects
				(font
					(size 1.27 1.27)
				)
			)
		)
		(duplicate_pad_numbers_are_jumpers no)
		(fp_line
			(start 0.7874 0.4064)
			(end -0.7874 0.4064)
			(stroke
				(width 0.1524)
				(type default)
			)
			(layer "F.SilkS")
		)
		(fp_line
			(start 0.7874 -0.4064)
			(end 0.7874 0.4064)
			(stroke
				(width 0.1524)
				(type default)
			)
			(layer "F.SilkS")
		)
		(fp_line
			(start -0.7874 0.4064)
			(end -0.7874 -0.4064)
			(stroke
				(width 0.1524)
				(type default)
			)
			(layer "F.SilkS")
		)
		(fp_line
			(start -0.7874 -0.4064)
			(end 0.7874 -0.4064)
			(stroke
				(width 0.1524)
				(type default)
			)
			(layer "F.SilkS")
		)
		(fp_line
			(start 0.67945 0.3048)
			(end 0.120396 0.3048)
			(stroke
				(width 0.1)
				(type default)
			)
			(layer "F.Fab")
		)
		(fp_line
			(start 0.67945 -0.3048)
			(end 0.67945 0.3048)
			(stroke
				(width 0.1)
				(type default)
			)
			(layer "F.Fab")
		)
		(fp_line
			(start 0.12065 -0.2794)
			(end 0.12065 -0.3048)
			(stroke
				(width 0.1)
				(type default)
			)
			(layer "F.Fab")
		)
		(fp_line
			(start 0.12065 -0.3048)
			(end 0.67945 -0.3048)
			(stroke
				(width 0.1)
				(type default)
			)
			(layer "F.Fab")
		)
		(fp_line
			(start 0.120396 0.3048)
			(end 0.120396 0.2794)
			(stroke
				(width 0.1)
				(type default)
			)
			(layer "F.Fab")
		)
		(fp_line
			(start 0.120396 0.2794)
			(end -0.12065 0.2794)
			(stroke
				(width 0.1)
				(type default)
			)
			(layer "F.Fab")
		)
		(fp_line
			(start -0.12065 0.3048)
			(end -0.67945 0.3048)
			(stroke
				(width 0.1)
				(type default)
			)
			(layer "F.Fab")
		)
		(fp_line
			(start -0.12065 0.2794)
			(end -0.12065 0.3048)
			(stroke
				(width 0.1)
				(type default)
			)
			(layer "F.Fab")
		)
		(fp_line
			(start -0.12065 -0.2794)
			(end 0.12065 -0.2794)
			(stroke
				(width 0.1)
				(type default)
			)
			(layer "F.Fab")
		)
		(fp_line
			(start -0.12065 -0.305054)
			(end -0.12065 -0.2794)
			(stroke
				(width 0.1)
				(type default)
			)
			(layer "F.Fab")
		)
		(fp_line
			(start -0.67945 0.3048)
			(end -0.67945 -0.305054)
			(stroke
				(width 0.1)
				(type default)
			)
			(layer "F.Fab")
		)
		(fp_line
			(start -0.67945 -0.305054)
			(end -0.12065 -0.305054)
			(stroke
				(width 0.1)
				(type default)
			)
			(layer "F.Fab")
		)
		(pad "1" smd circle
			(at -0.40005 0 180)
			(size 0 0)
			(layers "F.Cu" "F.Mask" "F.Paste")
			(net "FM_ID_LED")
		)
		(pad "2" smd circle
			(at 0.40005 0 180)
			(size 0 0)
			(layers "F.Cu" "F.Mask" "F.Paste")
			(net "FM_ID_R_LED")
		)
	)
	(footprint ""
		(layer "F.Cu")
		(at 10.287 -100.076 -90)
		(property "Reference" "R516"
			(at 0 0 270)
			(layer "F.SilkS")
			(hide yes)
			(effects
				(font
					(size 1.27 1.27)
				)
			)
		)
		(property "Value" ""
			(at 0 0 270)
			(layer "F.Fab")
			(effects
				(font
					(size 1.27 1.27)
				)
			)
		)
		(duplicate_pad_numbers_are_jumpers no)
		(fp_line
			(start -0.7874 0.4064)
			(end -0.7874 -0.4064)
			(stroke
				(width 0.1524)
				(type default)
			)
			(layer "F.SilkS")
		)
		(fp_line
			(start 0.7874 0.4064)
			(end -0.7874 0.4064)
			(stroke
				(width 0.1524)
				(type default)
			)
			(layer "F.SilkS")
		)
		(fp_line
			(start -0.7874 -0.4064)
			(end 0.7874 -0.4064)
			(stroke
				(width 0.1524)
				(type default)
			)
			(layer "F.SilkS")
		)
		(fp_line
			(start 0.7874 -0.4064)
			(end 0.7874 0.4064)
			(stroke
				(width 0.1524)
				(type default)
			)
			(layer "F.SilkS")
		)
		(fp_line
			(start -0.67945 0.3048)
			(end -0.67945 -0.305054)
			(stroke
				(width 0.1)
				(type default)
			)
			(layer "F.Fab")
		)
		(fp_line
			(start -0.12065 0.3048)
			(end -0.67945 0.3048)
			(stroke
				(width 0.1)
				(type default)
			)
			(layer "F.Fab")
		)
		(fp_line
			(start 0.120396 0.3048)
			(end 0.120396 0.2794)
			(stroke
				(width 0.1)
				(type default)
			)
			(layer "F.Fab")
		)
		(fp_line
			(start 0.67945 0.3048)
			(end 0.120396 0.3048)
			(stroke
				(width 0.1)
				(type default)
			)
			(layer "F.Fab")
		)
		(fp_line
			(start -0.12065 0.2794)
			(end -0.12065 0.3048)
			(stroke
				(width 0.1)
				(type default)
			)
			(layer "F.Fab")
		)
		(fp_line
			(start 0.120396 0.2794)
			(end -0.12065 0.2794)
			(stroke
				(width 0.1)
				(type default)
			)
			(layer "F.Fab")
		)
		(fp_line
			(start -0.12065 -0.2794)
			(end 0.12065 -0.2794)
			(stroke
				(width 0.1)
				(type default)
			)
			(layer "F.Fab")
		)
		(fp_line
			(start 0.12065 -0.2794)
			(end 0.12065 -0.3048)
			(stroke
				(width 0.1)
				(type default)
			)
			(layer "F.Fab")
		)
		(fp_line
			(start 0.12065 -0.3048)
			(end 0.67945 -0.3048)
			(stroke
				(width 0.1)
				(type default)
			)
			(layer "F.Fab")
		)
		(fp_line
			(start 0.67945 -0.3048)
			(end 0.67945 0.3048)
			(stroke
				(width 0.1)
				(type default)
			)
			(layer "F.Fab")
		)
		(fp_line
			(start -0.67945 -0.305054)
			(end -0.12065 -0.305054)
			(stroke
				(width 0.1)
				(type default)
			)
			(layer "F.Fab")
		)
		(fp_line
			(start -0.12065 -0.305054)
			(end -0.12065 -0.2794)
			(stroke
				(width 0.1)
				(type default)
			)
			(layer "F.Fab")
		)
		(pad "1" smd circle
			(at -0.40005 0 270)
			(size 0 0)
			(layers "F.Cu" "F.Mask" "F.Paste")
			(net "JTAG_SCM_PLD_TDI")
		)
		(pad "2" smd circle
			(at 0.40005 0 270)
			(size 0 0)
			(layers "F.Cu" "F.Mask" "F.Paste")
			(net "JTAG_SCM_CONN_TDI")
		)
	)
	(footprint ""
		(layer "F.Cu")
		(at 62.484 -30.861 90)
		(property "Reference" "R834"
			(at 0 0 90)
			(layer "F.SilkS")
			(hide yes)
			(effects
				(font
					(size 1.27 1.27)
				)
			)
		)
		(property "Value" ""
			(at 0 0 90)
			(layer "F.Fab")
			(effects
				(font
					(size 1.27 1.27)
				)
			)
		)
		(duplicate_pad_numbers_are_jumpers no)
		(fp_line
			(start 0.7874 -0.4064)
			(end 0.7874 0.4064)
			(stroke
				(width 0.1524)
				(type default)
			)
			(layer "F.SilkS")
		)
		(fp_line
			(start -0.7874 -0.4064)
			(end 0.7874 -0.4064)
			(stroke
				(width 0.1524)
				(type default)
			)
			(layer "F.SilkS")
		)
		(fp_line
			(start 0.7874 0.4064)
			(end -0.7874 0.4064)
			(stroke
				(width 0.1524)
				(type default)
			)
			(layer "F.SilkS")
		)
		(fp_line
			(start -0.7874 0.4064)
			(end -0.7874 -0.4064)
			(stroke
				(width 0.1524)
				(type default)
			)
			(layer "F.SilkS")
		)
		(fp_line
			(start -0.12065 -0.305054)
			(end -0.12065 -0.2794)
			(stroke
				(width 0.1)
				(type default)
			)
			(layer "F.Fab")
		)
		(fp_line
			(start -0.67945 -0.305054)
			(end -0.12065 -0.305054)
			(stroke
				(width 0.1)
				(type default)
			)
			(layer "F.Fab")
		)
		(fp_line
			(start 0.67945 -0.3048)
			(end 0.67945 0.3048)
			(stroke
				(width 0.1)
				(type default)
			)
			(layer "F.Fab")
		)
		(fp_line
			(start 0.12065 -0.3048)
			(end 0.67945 -0.3048)
			(stroke
				(width 0.1)
				(type default)
			)
			(layer "F.Fab")
		)
		(fp_line
			(start 0.12065 -0.2794)
			(end 0.12065 -0.3048)
			(stroke
				(width 0.1)
				(type default)
			)
			(layer "F.Fab")
		)
		(fp_line
			(start -0.12065 -0.2794)
			(end 0.12065 -0.2794)
			(stroke
				(width 0.1)
				(type default)
			)
			(layer "F.Fab")
		)
		(fp_line
			(start 0.120396 0.2794)
			(end -0.12065 0.2794)
			(stroke
				(width 0.1)
				(type default)
			)
			(layer "F.Fab")
		)
		(fp_line
			(start -0.12065 0.2794)
			(end -0.12065 0.3048)
			(stroke
				(width 0.1)
				(type default)
			)
			(layer "F.Fab")
		)
		(fp_line
			(start 0.67945 0.3048)
			(end 0.120396 0.3048)
			(stroke
				(width 0.1)
				(type default)
			)
			(layer "F.Fab")
		)
		(fp_line
			(start 0.120396 0.3048)
			(end 0.120396 0.2794)
			(stroke
				(width 0.1)
				(type default)
			)
			(layer "F.Fab")
		)
		(fp_line
			(start -0.12065 0.3048)
			(end -0.67945 0.3048)
			(stroke
				(width 0.1)
				(type default)
			)
			(layer "F.Fab")
		)
		(fp_line
			(start -0.67945 0.3048)
			(end -0.67945 -0.305054)
			(stroke
				(width 0.1)
				(type default)
			)
			(layer "F.Fab")
		)
		(pad "1" smd circle
			(at -0.40005 0 90)
			(size 0 0)
			(layers "F.Cu" "F.Mask" "F.Paste")
			(net "P3V3_RGM")
		)
		(pad "2" smd circle
			(at 0.40005 0 90)
			(size 0 0)
			(layers "F.Cu" "F.Mask" "F.Paste")
			(net "JTAG_SCM_TCK")
		)
	)
)
